# S9S_MB_2U (Grand Teton) — schematic netlist excerpt (pin names and nets, part order shuffled) for the footprints in the layout excerpt that follows; sources: Cadence DE-HDL packaged netlist, KiCad conversion of 03242023_DA0F0TMBIJ0_F0T_Motherboard_J_brd_V01_OCP.brd

R3895  Q_RES  49.9 1% CHIP  pkg 0402LF  page 102 : A = I3C_SPD_DDRABCD_CPU1_LVC1_SCL_4 ; B = I3C_SPD_DDRABCD_CPU1_LVC1_SCL
C386  Q_CAP  47UF 4V 20% X6S  pkg C0805  page 76 : A = PVCCIN_CPU0 ; B = GND
R2296  Q_RES  1K 1% CHIP  pkg 0402LF  page 191 : A = E1S_0_PWRDIS ; B = GND

(kicad_pcb
	(version 20260206)
	(generator "pcbnew")
	(generator_version "10.0")
	(general
		(thickness 1.6)
		(legacy_teardrops no)
	)
	(paper "A4")
	(title_block
		(title "03242023_DA0F0TMBIJ0_F0T_Motherboard_J_brd_V01_OCP.brd")
		(comment 1 "Grand Teton / footprints 6028-6030 of 6105")
	)
	(layers
		(0 "F.Cu" signal "TOP")
		(4 "In1.Cu" signal "GND")
		(6 "In2.Cu" signal "IN1")
		(8 "In3.Cu" signal "GND1")
		(10 "In4.Cu" signal "IN2")
		(12 "In5.Cu" signal "GND2")
		(14 "In6.Cu" signal "IN3")
		(16 "In7.Cu" signal "GND3")
		(18 "In8.Cu" signal "VCC")
		(20 "In9.Cu" signal "VCC1")
		(22 "In10.Cu" signal "GND4")
		(24 "In11.Cu" signal "IN4")
		(26 "In12.Cu" signal "GND5")
		(28 "In13.Cu" signal "IN5")
		(30 "In14.Cu" signal "GND6")
		(32 "In15.Cu" signal "IN6")
		(34 "In16.Cu" signal "GND7")
		(2 "B.Cu" signal "BOTTOM")
		(9 "F.Adhes" user "F.Adhesive")
		(11 "B.Adhes" user "B.Adhesive")
		(13 "F.Paste" user "Package Geometry/Pastemask Top")
		(15 "B.Paste" user "Package Geometry/Pastemask Bottom")
		(5 "F.SilkS" user "Ref Des/Silkscreen Top")
		(7 "B.SilkS" user "Ref Des/Silkscreen Bottom")
		(1 "F.Mask" user "Board Geometry/Soldermask Top")
		(3 "B.Mask" user "Board Geometry/Soldermask Bottom")
		(17 "Dwgs.User" user "User.Drawings")
		(19 "Cmts.User" user "User.Comments")
		(21 "Eco1.User" user "User.Eco1")
		(23 "Eco2.User" user "User.Eco2")
		(25 "Edge.Cuts" user "Board Geometry/Outline")
		(27 "Margin" user)
		(31 "F.CrtYd" user "Package Geometry/Place Bound Top")
		(29 "B.CrtYd" user "Package Geometry/Place Bound Bottom")
		(35 "F.Fab" user "Ref Des/Assembly Top")
		(33 "B.Fab" user "Ref Des/Assembly Bottom")
	)
	(footprint ""
		(layer "B.Cu")
		(at 236.20095 -51.209448)
		(property "Reference" "R2296"
			(at 0 0 0)
			(layer "B.SilkS")
			(hide yes)
			(effects
				(font
					(size 1.27 1.27)
				)
				(justify mirror)
			)
		)
		(property "Value" ""
			(at 0 0 0)
			(layer "B.Fab")
			(effects
				(font
					(size 1.27 1.27)
				)
				(justify mirror)
			)
		)
		(duplicate_pad_numbers_are_jumpers no)
		(fp_line
			(start -0.7874 -0.4064)
			(end -0.7874 0.4064)
			(stroke
				(width 0.1524)
				(type default)
			)
			(layer "B.SilkS")
		)
		(fp_line
			(start -0.7874 0.4064)
			(end 0.7874 0.4064)
			(stroke
				(width 0.1524)
				(type default)
			)
			(layer "B.SilkS")
		)
		(fp_line
			(start 0.7874 -0.4064)
			(end -0.7874 -0.4064)
			(stroke
				(width 0.1524)
				(type default)
			)
			(layer "B.SilkS")
		)
		(fp_line
			(start 0.7874 0.4064)
			(end 0.7874 -0.4064)
			(stroke
				(width 0.1524)
				(type default)
			)
			(layer "B.SilkS")
		)
		(fp_line
			(start -0.67945 -0.3048)
			(end -0.67945 0.3048)
			(stroke
				(width 0.1)
				(type default)
			)
			(layer "B.Fab")
		)
		(fp_line
			(start -0.67945 0.3048)
			(end -0.120396 0.3048)
			(stroke
				(width 0.1)
				(type default)
			)
			(layer "B.Fab")
		)
		(fp_line
			(start -0.12065 -0.3048)
			(end -0.67945 -0.3048)
			(stroke
				(width 0.1)
				(type default)
			)
			(layer "B.Fab")
		)
		(fp_line
			(start -0.12065 -0.2794)
			(end -0.12065 -0.3048)
			(stroke
				(width 0.1)
				(type default)
			)
			(layer "B.Fab")
		)
		(fp_line
			(start -0.120396 0.2794)
			(end 0.12065 0.2794)
			(stroke
				(width 0.1)
				(type default)
			)
			(layer "B.Fab")
		)
		(fp_line
			(start -0.120396 0.3048)
			(end -0.120396 0.2794)
			(stroke
				(width 0.1)
				(type default)
			)
			(layer "B.Fab")
		)
		(fp_line
			(start 0.12065 -0.305054)
			(end 0.12065 -0.2794)
			(stroke
				(width 0.1)
				(type default)
			)
			(layer "B.Fab")
		)
		(fp_line
			(start 0.12065 -0.2794)
			(end -0.12065 -0.2794)
			(stroke
				(width 0.1)
				(type default)
			)
			(layer "B.Fab")
		)
		(fp_line
			(start 0.12065 0.2794)
			(end 0.12065 0.3048)
			(stroke
				(width 0.1)
				(type default)
			)
			(layer "B.Fab")
		)
		(fp_line
			(start 0.12065 0.3048)
			(end 0.67945 0.3048)
			(stroke
				(width 0.1)
				(type default)
			)
			(layer "B.Fab")
		)
		(fp_line
			(start 0.67945 -0.305054)
			(end 0.12065 -0.305054)
			(stroke
				(width 0.1)
				(type default)
			)
			(layer "B.Fab")
		)
		(fp_line
			(start 0.67945 0.3048)
			(end 0.67945 -0.305054)
			(stroke
				(width 0.1)
				(type default)
			)
			(layer "B.Fab")
		)
		(pad "1" smd circle
			(at 0.40005 0 180)
			(size 0 0)
			(layers "B.Cu" "B.Mask" "B.Paste")
			(net "E1S_0_PWRDIS")
		)
		(pad "2" smd circle
			(at -0.40005 0 180)
			(size 0 0)
			(layers "B.Cu" "B.Mask" "B.Paste")
			(net "GND")
		)
	)
	(footprint ""
		(layer "B.Cu")
		(at 23.145242 -316.36589 90)
		(property "Reference" "R3895"
			(at 0 0 90)
			(layer "B.SilkS")
			(hide yes)
			(effects
				(font
					(size 1.27 1.27)
				)
				(justify mirror)
			)
		)
		(property "Value" ""
			(at 0 0 90)
			(layer "B.Fab")
			(effects
				(font
					(size 1.27 1.27)
				)
				(justify mirror)
			)
		)
		(duplicate_pad_numbers_are_jumpers no)
		(fp_line
			(start 0.7874 -0.4064)
			(end -0.7874 -0.4064)
			(stroke
				(width 0.1524)
				(type default)
			)
			(layer "B.SilkS")
		)
		(fp_line
			(start -0.7874 -0.4064)
			(end -0.7874 0.4064)
			(stroke
				(width 0.1524)
				(type default)
			)
			(layer "B.SilkS")
		)
		(fp_line
			(start 0.7874 0.4064)
			(end 0.7874 -0.4064)
			(stroke
				(width 0.1524)
				(type default)
			)
			(layer "B.SilkS")
		)
		(fp_line
			(start -0.7874 0.4064)
			(end 0.7874 0.4064)
			(stroke
				(width 0.1524)
				(type default)
			)
			(layer "B.SilkS")
		)
		(fp_line
			(start 0.67945 -0.305054)
			(end 0.12065 -0.305054)
			(stroke
				(width 0.1)
				(type default)
			)
			(layer "B.Fab")
		)
		(fp_line
			(start 0.12065 -0.305054)
			(end 0.12065 -0.2794)
			(stroke
				(width 0.1)
				(type default)
			)
			(layer "B.Fab")
		)
		(fp_line
			(start -0.12065 -0.3048)
			(end -0.67945 -0.3048)
			(stroke
				(width 0.1)
				(type default)
			)
			(layer "B.Fab")
		)
		(fp_line
			(start -0.67945 -0.3048)
			(end -0.67945 0.3048)
			(stroke
				(width 0.1)
				(type default)
			)
			(layer "B.Fab")
		)
		(fp_line
			(start 0.12065 -0.2794)
			(end -0.12065 -0.2794)
			(stroke
				(width 0.1)
				(type default)
			)
			(layer "B.Fab")
		)
		(fp_line
			(start -0.12065 -0.2794)
			(end -0.12065 -0.3048)
			(stroke
				(width 0.1)
				(type default)
			)
			(layer "B.Fab")
		)
		(fp_line
			(start 0.12065 0.2794)
			(end 0.12065 0.3048)
			(stroke
				(width 0.1)
				(type default)
			)
			(layer "B.Fab")
		)
		(fp_line
			(start -0.120396 0.2794)
			(end 0.12065 0.2794)
			(stroke
				(width 0.1)
				(type default)
			)
			(layer "B.Fab")
		)
		(fp_line
			(start 0.67945 0.3048)
			(end 0.67945 -0.305054)
			(stroke
				(width 0.1)
				(type default)
			)
			(layer "B.Fab")
		)
		(fp_line
			(start 0.12065 0.3048)
			(end 0.67945 0.3048)
			(stroke
				(width 0.1)
				(type default)
			)
			(layer "B.Fab")
		)
		(fp_line
			(start -0.120396 0.3048)
			(end -0.120396 0.2794)
			(stroke
				(width 0.1)
				(type default)
			)
			(layer "B.Fab")
		)
		(fp_line
			(start -0.67945 0.3048)
			(end -0.120396 0.3048)
			(stroke
				(width 0.1)
				(type default)
			)
			(layer "B.Fab")
		)
		(pad "1" smd circle
			(at 0.40005 0 270)
			(size 0 0)
			(layers "B.Cu" "B.Mask" "B.Paste")
			(net "I3C_SPD_DDRABCD_CPU1_LVC1_SCL_4")
		)
		(pad "2" smd circle
			(at -0.40005 0 270)
			(size 0 0)
			(layers "B.Cu" "B.Mask" "B.Paste")
			(net "I3C_SPD_DDRABCD_CPU1_LVC1_SCL")
		)
	)
	(footprint ""
		(layer "B.Cu")
		(at 350.435418 -296.054526 180)
		(property "Reference" "C386"
			(at 0 0 0)
			(layer "B.SilkS")
			(hide yes)
			(effects
				(font
					(size 1.27 1.27)
				)
				(justify mirror)
			)
		)
		(property "Value" ""
			(at 0 0 0)
			(layer "B.Fab")
			(effects
				(font
					(size 1.27 1.27)
				)
				(justify mirror)
			)
		)
		(duplicate_pad_numbers_are_jumpers no)
		(fp_line
			(start 1.524 0.762)
			(end 1.524 -0.762)
			(stroke
				(width 0.1524)
				(type default)
			)
			(layer "B.SilkS")
		)
		(fp_line
			(start 1.524 -0.762)
			(end -1.524 -0.762)
			(stroke
				(width 0.1524)
				(type default)
			)
			(layer "B.SilkS")
		)
		(fp_line
			(start -1.524 0.762)
			(end 1.524 0.762)
			(stroke
				(width 0.1524)
				(type default)
			)
			(layer "B.SilkS")
		)
		(fp_line
			(start -1.524 -0.762)
			(end -1.524 0.762)
			(stroke
				(width 0.1524)
				(type default)
			)
			(layer "B.SilkS")
		)
		(fp_line
			(start 1.1049 0.724916)
			(end -1.1049 0.724916)
			(stroke
				(width 0.1)
				(type default)
			)
			(layer "B.Fab")
		)
		(fp_line
			(start 1.1049 -0.724916)
			(end 1.1049 0.724916)
			(stroke
				(width 0.1)
				(type default)
			)
			(layer "B.Fab")
		)
		(fp_line
			(start -1.1049 0.724916)
			(end -1.1049 -0.724916)
			(stroke
				(width 0.1)
				(type default)
			)
			(layer "B.Fab")
		)
		(fp_line
			(start -1.1049 -0.724916)
			(end 1.1049 -0.724916)
			(stroke
				(width 0.1)
				(type default)
			)
			(layer "B.Fab")
		)
		(pad "1" smd rect
			(at 0.889 0 180)
			(size 1.016 1.27)
			(layers "B.Cu" "B.Mask" "B.Paste")
			(net "PVCCIN_CPU0")
		)
		(pad "2" smd rect
			(at -0.889 0 180)
			(size 1.016 1.27)
			(layers "B.Cu" "B.Mask" "B.Paste")
			(net "GND")
		)
	)
)
